(kicad_pcb
	(version 20260206)
	(generator "pcbnew")
	(generator_version "10.0")
	(general
		(thickness 1.6)
		(legacy_teardrops no)
	)
	(paper "A4")
	(title_block
		(title "01162023_DA0F0TEBIF0_F0T_Expander_BD_F_brd_V02_OCP.brd")
		(comment 1 "Grand Teton / footprints 3060-3060 of 9728")
	)
	(layers
		(0 "F.Cu" signal "TOP")
		(4 "In1.Cu" signal "GND")
		(6 "In2.Cu" signal "VCC")
		(8 "In3.Cu" signal "VCC1")
		(10 "In4.Cu" signal "GND1")
		(12 "In5.Cu" signal "IN1")
		(14 "In6.Cu" signal "GND2")
		(16 "In7.Cu" signal "IN2")
		(18 "In8.Cu" signal "GND3")
		(20 "In9.Cu" signal "IN3")
		(22 "In10.Cu" signal "GND4")
		(24 "In11.Cu" signal "IN4")
		(26 "In12.Cu" signal "GND5")
		(28 "In13.Cu" signal "IN5")
		(30 "In14.Cu" signal "GND6")
		(32 "In15.Cu" signal "IN6")
		(34 "In16.Cu" signal "GND7")
		(2 "B.Cu" signal "BOTTOM")
		(9 "F.Adhes" user "F.Adhesive")
		(11 "B.Adhes" user "B.Adhesive")
		(13 "F.Paste" user "Package Geometry/Pastemask Top")
		(15 "B.Paste" user "Package Geometry/Pastemask Bottom")
		(5 "F.SilkS" user "Ref Des/Silkscreen Top")
		(7 "B.SilkS" user "Ref Des/Silkscreen Bottom")
		(1 "F.Mask" user "Board Geometry/Soldermask Top")
		(3 "B.Mask" user "Board Geometry/Soldermask Bottom")
		(17 "Dwgs.User" user "User.Drawings")
		(19 "Cmts.User" user "User.Comments")
		(21 "Eco1.User" user "User.Eco1")
		(23 "Eco2.User" user "User.Eco2")
		(25 "Edge.Cuts" user "Board Geometry/Outline")
		(27 "Margin" user)
		(31 "F.CrtYd" user "Package Geometry/Place Bound Top")
		(29 "B.CrtYd" user "Package Geometry/Place Bound Bottom")
		(35 "F.Fab" user "Ref Des/Assembly Top")
		(33 "B.Fab" user "Ref Des/Assembly Bottom")
	)
	(footprint ""
		(layer "F.Cu")
		(at 329.83297 -98.968052 -90)
		(property "Reference" "PU25"
			(at 1.270762 2.350516 90)
			(unlocked yes)
			(layer "F.SilkS")
			(effects
				(font
					(size 0.7874 0.5842)
					(thickness 0.1524)
				)
				(justify left)
			)
		)
		(property "Value" ""
			(at 0 0 270)
			(layer "F.Fab")
			(effects
				(font
					(size 1.27 1.27)
				)
			)
		)
		(duplicate_pad_numbers_are_jumpers no)
		(fp_line
			(start -1.943608 1.549908)
			(end -1.943608 -1.549908)
			(stroke
				(width 0.1524)
				(type default)
			)
			(layer "F.SilkS")
		)
		(fp_line
			(start 1.943608 1.549908)
			(end -1.943608 1.549908)
			(stroke
				(width 0.1524)
				(type default)
			)
			(layer "F.SilkS")
		)
		(fp_line
			(start -1.943608 -1.549908)
			(end 1.943608 -1.549908)
			(stroke
				(width 0.1524)
				(type default)
			)
			(layer "F.SilkS")
		)
		(fp_line
			(start 1.943608 -1.549908)
			(end 1.943608 1.549908)
			(stroke
				(width 0.1524)
				(type default)
			)
			(layer "F.SilkS")
		)
		(fp_poly
			(pts
				(xy -2.019808 -1.549908) (xy -1.257808 -1.549908) (xy -1.257808 -1.880108) (xy -2.019808 -1.880108)
			)
			(stroke
				(width 0)
				(type default)
			)
			(fill yes)
			(layer "F.SilkS")
		)
		(fp_line
			(start -1.549908 1.549908)
			(end -1.549908 -1.549908)
			(stroke
				(width 0.1)
				(type default)
			)
			(layer "F.Fab")
		)
		(fp_line
			(start 1.549908 1.549908)
			(end -1.549908 1.549908)
			(stroke
				(width 0.1)
				(type default)
			)
			(layer "F.Fab")
		)
		(fp_line
			(start -1.549908 -1.549908)
			(end 1.549908 -1.549908)
			(stroke
				(width 0.1)
				(type default)
			)
			(layer "F.Fab")
		)
		(fp_line
			(start 1.549908 -1.549908)
			(end 1.549908 1.549908)
			(stroke
				(width 0.1)
				(type default)
			)
			(layer "F.Fab")
		)
		(fp_poly
			(pts
				(xy -2.019808 -1.549908) (xy -1.257808 -1.549908) (xy -1.257808 -1.880108) (xy -2.019808 -1.880108)
			)
			(stroke
				(width 0)
				(type default)
			)
			(fill yes)
			(layer "F.Fab")
		)
		(pad "1" smd rect
			(at -1.500124 -1.249934 180)
			(size 0.2794 0.6096)
			(layers "F.Cu" "F.Mask" "F.Paste")
			(net "P12V_NIC5_R")
		)
		(pad "2" smd rect
			(at -1.500124 -0.750062 180)
			(size 0.2794 0.6096)
			(layers "F.Cu" "F.Mask" "F.Paste")
			(net "P12V_NIC5_R")
		)
		(pad "3" smd rect
			(at -1.500124 -0.249936 180)
			(size 0.2794 0.6096)
			(layers "F.Cu" "F.Mask" "F.Paste")
			(net "P12V_NIC5_R")
		)
		(pad "4" smd rect
			(at -1.500124 0.249936 180)
			(size 0.2794 0.6096)
			(layers "F.Cu" "F.Mask" "F.Paste")
			(net "P12V_NIC5_R")
		)
		(pad "5" smd rect
			(at -1.500124 0.750062 180)
			(size 0.2794 0.6096)
			(layers "F.Cu" "F.Mask" "F.Paste")
			(net "P12V_NIC5_R")
		)
		(pad "6" smd rect
			(at -1.500124 1.249934 180)
			(size 0.2794 0.6096)
			(layers "F.Cu" "F.Mask" "F.Paste")
			(net "GND")
		)
		(pad "7" smd rect
			(at 1.500124 1.249934 180)
			(size 0.2794 0.6096)
			(layers "F.Cu" "F.Mask" "F.Paste")
			(net "P12V_NIC5_SS")
		)
		(pad "8" smd rect
			(at 1.500124 0.750062 180)
			(size 0.2794 0.6096)
			(layers "F.Cu" "F.Mask" "F.Paste")
			(net "PWRGD_P12V_NIC5")
		)
		(pad "9" smd rect
			(at 1.500124 0.249936 180)
			(size 0.2794 0.6096)
			(layers "F.Cu" "F.Mask" "F.Paste")
			(net "P12V_NIC5_OCP")
		)
		(pad "10" smd rect
			(at 1.500124 -0.249936 180)
			(size 0.2794 0.6096)
			(layers "F.Cu" "F.Mask" "F.Paste")
			(net "P5V_AUX")
		)
		(pad "11" smd rect
			(at 1.500124 -0.750062 180)
			(size 0.2794 0.6096)
			(layers "F.Cu" "F.Mask" "F.Paste")
			(net "P12V_NIC5_EN_R")
		)
		(pad "12" smd rect
			(at 1.500124 -1.249934 180)
			(size 0.2794 0.6096)
			(layers "F.Cu" "F.Mask" "F.Paste")
			(net "P12V_AUX")
		)
		(pad "13" smd rect
			(at 0 0 270)
			(size 1.9812 2.7178)
			(layers "F.Cu" "F.Mask" "F.Paste")
			(net "P12V_AUX")
		)
		(zone
			(layer "F.Cu")
			(hatch none 0.5)
			(connect_pads
				(clearance 0)
			)
			(min_thickness 0.25)
			(keepout
				(tracks not_allowed)
				(vias allowed)
				(pads allowed)
				(copperpour not_allowed)
				(footprints allowed)
			)
			(placement
				(enabled no)
				(sheetname "")
			)
			(fill
				(thermal_gap 0.5)
				(thermal_bridge_width 0.5)
				(island_removal_mode 0)
			)
			(polygon
				(pts
					(xy 331.38237 -97.825052) (xy 331.25537 -97.825052) (xy 328.28357 -97.825052) (xy 328.283062 -97.825052)
					(xy 328.283062 -100.111052) (xy 328.28357 -100.111052) (xy 328.41057 -100.111052) (xy 329.83297 -100.111052)
					(xy 329.83297 -100.009452) (xy 328.41057 -100.009452) (xy 328.41057 -97.926652) (xy 331.25537 -97.926652)
					(xy 331.25537 -100.009452) (xy 329.85837 -100.009452) (xy 329.85837 -100.111052) (xy 331.25537 -100.111052)
					(xy 331.38237 -100.111052) (xy 331.382878 -100.111052) (xy 331.382878 -97.825052)
				)
			)
		)
	)
)
